G04 ================== begin FILE IDENTIFICATION RECORD ==================*
G04 Layout Name:  12432-1.brd*
G04 Film Name:    BSILK*
G04 File Format:  Gerber RS274X*
G04 File Origin:  Cadence Allegro 16.2-S037*
G04 Origin Date:  Wed Oct 17 10:59:39 2012*
G04 *
G04 Layer:  VIA CLASS/FILMMASKBOTTOM*
G04 Layer:  REF DES/ASSEMBLY_BOTTOM*
G04 Layer:  PACKAGE GEOMETRY/SILKSCREEN_BOTTOM*
G04 Layer:  DRAWING FORMAT/LAYER_PCB_STORY*
G04 Layer:  DRAWING FORMAT/LAYER_SILK_B*
G04 Layer:  BOARD GEOMETRY/SILKSCREEN_BOTTOM*
G04 *
G04 Offset:    (0.00 0.00)*
G04 Mirror:    No*
G04 Mode:      Positive*
G04 Rotation:  0*
G04 FullContactRelief:  No*
G04 UndefLineWidth:     6.00*
G04 ================== end FILE IDENTIFICATION RECORD ====================*
%FSLAX35Y35*MOIN*%
%IR0*IPPOS*OFA0.00000B0.00000*MIA0B0*SFA1.00000B1.00000*%
%ADD10C,.026*%
%ADD11C,.02*%
%ADD12C,.012*%
%ADD13C,.006*%
G75*
%LPD*%
G75*
G54D10*
X34799Y1946750D03*
X38703Y1946754D03*
X44368Y1951450D03*
X44399Y1942250D03*
X42532Y1946783D03*
X53999Y1946650D03*
X50299D03*
X46565Y1946703D03*
X205938Y72528D03*
X210605Y70692D03*
X210685Y74725D03*
X215138Y72559D03*
X210634Y66863D03*
X210638Y62959D03*
X210738Y82159D03*
Y78459D03*
X923761Y85550D03*
X928561Y95181D03*
X928428Y83714D03*
X928508Y87747D03*
X928561Y91481D03*
X928457Y79885D03*
X928461Y75981D03*
X932961Y85581D03*
G54D11*
G01X-87137Y-139897D02*
Y-107897D01*
G01X-75137Y-123897D02*
G02I-12000J0D01*
G01X-80287D02*
G02I-6850J0D01*
G01X-71137D02*
X-103137D01*
G01X-71137Y-139897D02*
Y-219897D01*
G01D02*
X1129963D01*
G01X-71137Y-175397D02*
X1129963D01*
G01X-71137Y-139897D02*
X1129963D01*
G01X342463D02*
Y-219897D01*
G01X479963Y-139897D02*
Y-219897D01*
G01X594963Y-139897D02*
Y-219897D01*
G01X762463Y-139897D02*
Y-219897D01*
G01X932463Y-139897D02*
Y-219897D01*
G01X1129963Y-139897D02*
Y-219897D01*
G01X1157963Y-123897D02*
G02I-12000J0D01*
G01X1152813D02*
G02I-6850J0D01*
G01X1161963D02*
X1129963D01*
G01X1145963Y-139897D02*
Y-107897D01*
G54D12*
G01X0Y41772D02*
Y17214D01*
G01Y191667D02*
Y167110D01*
G01Y332003D02*
Y308383D01*
G01Y753542D02*
Y724169D01*
G01Y933234D02*
Y905988D01*
G01Y1129921D02*
Y1106301D01*
G01Y1309889D02*
Y1280567D01*
G01Y1738015D02*
Y1707948D01*
G01Y1912843D02*
Y1889223D01*
G01Y1986547D02*
Y1962927D01*
G01X1033464Y48297D02*
Y24677D01*
G01X1033465Y240964D02*
Y217344D01*
G01Y468660D02*
Y445040D01*
G01Y721094D02*
Y697474D01*
G01Y721094D02*
Y697474D01*
G01Y1020472D02*
Y996852D01*
G01Y1367680D02*
Y1344060D01*
G01Y1763340D02*
Y1739720D01*
G01X1033464Y1982862D02*
Y1959242D01*
G54D13*
G01X-53190Y-209897D02*
Y-192397D01*
G01X-44894D02*
X-53190Y-203189D01*
G01X-43584Y-209897D02*
X-49479Y-198231D01*
G01X-35909Y-209897D02*
Y-192397D01*
X-25865Y-209897D01*
Y-192397D01*
G01X-13387Y-209897D02*
X-15134Y-209605D01*
X-16662Y-208439D01*
X-17972Y-206689D01*
X-18846Y-204647D01*
X-19282Y-202314D01*
Y-199980D01*
X-18846Y-197647D01*
X-17972Y-195605D01*
X-16662Y-193856D01*
X-15134Y-192689D01*
X-13387Y-192397D01*
X-11641Y-192689D01*
X-10112Y-193856D01*
X-8802Y-195605D01*
X-7928Y-197647D01*
X-7492Y-199980D01*
Y-202314D01*
X-7928Y-204647D01*
X-8802Y-206689D01*
X-10112Y-208439D01*
X-11641Y-209605D01*
X-13387Y-209897D01*
G01X-472D02*
X8698Y-192397D01*
G01X-472D02*
X8698Y-209897D01*
G01X34310D02*
Y-192397D01*
X38676D01*
X40423Y-193272D01*
X41733Y-194439D01*
X42825Y-196188D01*
X43698Y-198231D01*
X43916Y-201147D01*
X43698Y-204064D01*
X42825Y-206106D01*
X41733Y-207856D01*
X40423Y-209022D01*
X38676Y-209897D01*
X34310D01*
G01X52246D02*
Y-192397D01*
X57705D01*
X59451Y-193272D01*
X60543Y-194439D01*
X60980Y-196772D01*
X60543Y-199106D01*
X59233Y-200564D01*
X57705Y-201439D01*
X52246D01*
G01X57705D02*
X60980Y-209897D01*
G01X71493Y-192397D02*
X76733D01*
G01X74113D02*
Y-209897D01*
G01X71493D02*
X76733D01*
G01X86154Y-192397D02*
X91613Y-209897D01*
X97072Y-192397D01*
G01X113480Y-209897D02*
X104746D01*
Y-192397D01*
X113480D01*
G01X109986Y-200855D02*
X104746D01*
G01X139746Y-209897D02*
Y-192397D01*
X144986D01*
X146733Y-193272D01*
X148043Y-195314D01*
X148480Y-197647D01*
X148043Y-199980D01*
X146951Y-201730D01*
X144986Y-202606D01*
X139746D01*
G01X157246Y-192397D02*
Y-209897D01*
X165980D01*
G01X173654D02*
X179113Y-192397D01*
X184572Y-209897D01*
G01X182606Y-203772D02*
X175619D01*
G01X191591Y-209897D02*
Y-192397D01*
X201635Y-209897D01*
Y-192397D01*
G01X218480Y-209897D02*
X209746D01*
Y-192397D01*
X218480D01*
G01X214986Y-200855D02*
X209746D01*
G01X250859Y-200564D02*
X251733Y-199689D01*
X252388Y-198231D01*
X252825Y-196188D01*
X252388Y-194439D01*
X251515Y-193272D01*
X249986Y-192397D01*
X244091D01*
Y-209897D01*
X251296D01*
X252825Y-208731D01*
X253698Y-206980D01*
X254135Y-204939D01*
X253698Y-202897D01*
X252388Y-201147D01*
X250859Y-200564D01*
X244091D01*
G01X266613Y-209897D02*
X264866Y-209605D01*
X263338Y-208439D01*
X262028Y-206689D01*
X261154Y-204647D01*
X260718Y-202314D01*
Y-199980D01*
X261154Y-197647D01*
X262028Y-195605D01*
X263338Y-193856D01*
X264866Y-192689D01*
X266613Y-192397D01*
X268359Y-192689D01*
X269888Y-193856D01*
X271198Y-195605D01*
X272072Y-197647D01*
X272508Y-199980D01*
Y-202314D01*
X272072Y-204647D01*
X271198Y-206689D01*
X269888Y-208439D01*
X268359Y-209605D01*
X266613Y-209897D01*
G01X278654D02*
X284113Y-192397D01*
X289572Y-209897D01*
G01X287606Y-203772D02*
X280619D01*
G01X297246Y-209897D02*
Y-192397D01*
X302705D01*
X304451Y-193272D01*
X305543Y-194439D01*
X305980Y-196772D01*
X305543Y-199106D01*
X304233Y-200564D01*
X302705Y-201439D01*
X297246D01*
G01X302705D02*
X305980Y-209897D01*
G01X314310D02*
Y-192397D01*
X318676D01*
X320423Y-193272D01*
X321733Y-194439D01*
X322825Y-196188D01*
X323698Y-198231D01*
X323916Y-201147D01*
X323698Y-204064D01*
X322825Y-206106D01*
X321733Y-207856D01*
X320423Y-209022D01*
X318676Y-209897D01*
X314310D01*
G01X94686Y-164897D02*
Y-147397D01*
X100363Y-161980D01*
X106040Y-147397D01*
Y-164897D01*
G01X117863D02*
X116553Y-164605D01*
X115243Y-163439D01*
X114369Y-161397D01*
X113933Y-159064D01*
X114369Y-156730D01*
X115243Y-154689D01*
X116553Y-153522D01*
X117863Y-153231D01*
X119173Y-153522D01*
X120483Y-154689D01*
X121356Y-156730D01*
X121575Y-159064D01*
X121356Y-161397D01*
X120483Y-163439D01*
X119173Y-164605D01*
X117863Y-164897D01*
G01X139293Y-147397D02*
Y-164897D01*
G01Y-162273D02*
X138420Y-163731D01*
X137109Y-164605D01*
X135581Y-164897D01*
X133835Y-164314D01*
X132525Y-162856D01*
X131651Y-161106D01*
X131433Y-159064D01*
X131651Y-157022D01*
X132525Y-155272D01*
X133835Y-153814D01*
X135581Y-153231D01*
X137109Y-153522D01*
X138201Y-154106D01*
X139293Y-155272D01*
G01X149588Y-157022D02*
X156575D01*
X155920Y-154980D01*
X154828Y-153814D01*
X153300Y-153231D01*
X151771Y-153522D01*
X150461Y-154397D01*
X149588Y-156439D01*
X149151Y-158189D01*
Y-159939D01*
X149588Y-161689D01*
X150680Y-163439D01*
X151990Y-164605D01*
X153518Y-164897D01*
X155046Y-164314D01*
X156575Y-162564D01*
G01X170363Y-164897D02*
Y-147397D01*
G01X376163Y-209897D02*
Y-192397D01*
X373543Y-195897D01*
G01Y-209897D02*
X378783D01*
G01X389515Y-195314D02*
X390825Y-193564D01*
X392353Y-192689D01*
X394100Y-192397D01*
X396283Y-192980D01*
X397811Y-194439D01*
X398248Y-196188D01*
X398030Y-197939D01*
X397156Y-199397D01*
X392790Y-202314D01*
X390825Y-204355D01*
X389515Y-207273D01*
X389078Y-209897D01*
X398248D01*
G01X413783D02*
Y-192397D01*
X405704Y-204939D01*
X416622D01*
G01X423860Y-206397D02*
X425169Y-208439D01*
X426916Y-209605D01*
X428881Y-209897D01*
X430628Y-209605D01*
X432375Y-208147D01*
X433466Y-206397D01*
X433685Y-204647D01*
X433248Y-202606D01*
X431720Y-201147D01*
X430191Y-200564D01*
X428226D01*
G01X430191D02*
X431501Y-199689D01*
X432593Y-198231D01*
X433030Y-196481D01*
X432593Y-194730D01*
X431501Y-193272D01*
X429536Y-192397D01*
X427571Y-192689D01*
X425606Y-193856D01*
G01X442015Y-195314D02*
X443325Y-193564D01*
X444853Y-192689D01*
X446600Y-192397D01*
X448783Y-192980D01*
X450311Y-194439D01*
X450748Y-196188D01*
X450530Y-197939D01*
X449656Y-199397D01*
X445290Y-202314D01*
X443325Y-204355D01*
X442015Y-207273D01*
X441578Y-209897D01*
X450748D01*
G01X363046Y-164897D02*
Y-147397D01*
X368286D01*
X370033Y-148272D01*
X371343Y-150314D01*
X371780Y-152647D01*
X371343Y-154980D01*
X370251Y-156730D01*
X368286Y-157606D01*
X363046D01*
G01X389716Y-148856D02*
X388406Y-147980D01*
X386878Y-147397D01*
X385131D01*
X383166Y-148272D01*
X381638Y-149730D01*
X380546Y-151481D01*
X379673Y-154397D01*
X379454Y-157022D01*
X379891Y-159647D01*
X380546Y-161397D01*
X381856Y-163147D01*
X383385Y-164314D01*
X384913Y-164897D01*
X386441D01*
X387970Y-164314D01*
X389280Y-163439D01*
X390372Y-162273D01*
G01X404159Y-155564D02*
X405033Y-154689D01*
X405688Y-153231D01*
X406125Y-151188D01*
X405688Y-149439D01*
X404815Y-148272D01*
X403286Y-147397D01*
X397391D01*
Y-164897D01*
X404596D01*
X406125Y-163731D01*
X406998Y-161980D01*
X407435Y-159939D01*
X406998Y-157897D01*
X405688Y-156147D01*
X404159Y-155564D01*
X397391D01*
G01X413363Y-170730D02*
X426463D01*
G01X432391Y-164897D02*
Y-147397D01*
X442435Y-164897D01*
Y-147397D01*
G01X454913Y-164897D02*
X453166Y-164605D01*
X451638Y-163439D01*
X450328Y-161689D01*
X449454Y-159647D01*
X449018Y-157314D01*
Y-154980D01*
X449454Y-152647D01*
X450328Y-150605D01*
X451638Y-148856D01*
X453166Y-147689D01*
X454913Y-147397D01*
X456659Y-147689D01*
X458188Y-148856D01*
X459498Y-150605D01*
X460372Y-152647D01*
X460808Y-154980D01*
Y-157314D01*
X460372Y-159647D01*
X459498Y-161689D01*
X458188Y-163439D01*
X456659Y-164605D01*
X454913Y-164897D01*
G01X505754Y-147397D02*
X511213Y-164897D01*
X516672Y-147397D01*
G01X533080Y-164897D02*
X524346D01*
Y-147397D01*
X533080D01*
G01X529586Y-155855D02*
X524346D01*
G01X541846Y-164897D02*
Y-147397D01*
X547305D01*
X549051Y-148272D01*
X550143Y-149439D01*
X550580Y-151772D01*
X550143Y-154106D01*
X548833Y-155564D01*
X547305Y-156439D01*
X541846D01*
G01X547305D02*
X550580Y-164897D01*
G01X563713Y-165480D02*
X563276Y-165189D01*
Y-164605D01*
X563713Y-164314D01*
X564150Y-164605D01*
Y-165189D01*
X563713Y-165480D01*
G01X537463Y-209897D02*
Y-192397D01*
X534843Y-195897D01*
G01Y-209897D02*
X540083D01*
G01X630546Y-147397D02*
Y-164897D01*
X639280D01*
G01X656343D02*
Y-153231D01*
G01Y-155272D02*
X655470Y-154106D01*
X654159Y-153522D01*
X652631Y-153231D01*
X651103Y-153814D01*
X649793Y-154980D01*
X648919Y-156730D01*
X648483Y-159064D01*
X648919Y-161397D01*
X649793Y-163147D01*
X651103Y-164314D01*
X652631Y-164897D01*
X654159Y-164605D01*
X655470Y-163731D01*
X656343Y-162564D01*
G01X665328Y-170147D02*
X666638Y-170730D01*
X668385Y-170147D01*
X669476Y-168981D01*
X670350Y-167522D01*
X671659Y-162856D01*
X674498Y-153231D01*
G01X667511D02*
X671659Y-162856D01*
G01X684138Y-157022D02*
X691125D01*
X690470Y-154980D01*
X689378Y-153814D01*
X687850Y-153231D01*
X686321Y-153522D01*
X685011Y-154397D01*
X684138Y-156439D01*
X683701Y-158189D01*
Y-159939D01*
X684138Y-161689D01*
X685230Y-163439D01*
X686540Y-164605D01*
X688068Y-164897D01*
X689596Y-164314D01*
X691125Y-162564D01*
G01X701856Y-164897D02*
Y-153231D01*
G01Y-155564D02*
X702948Y-154397D01*
X704040Y-153522D01*
X705568Y-153231D01*
X706659Y-153522D01*
X707970Y-154397D01*
G01X719138Y-162856D02*
X720230Y-164022D01*
X721758Y-164897D01*
X723068D01*
X724378Y-164314D01*
X725251Y-163439D01*
X725688Y-162273D01*
X725470Y-160522D01*
X724596Y-159647D01*
X720666Y-157897D01*
X719793Y-155855D01*
X720230Y-154397D01*
X721103Y-153522D01*
X722413Y-153231D01*
X723723Y-153522D01*
X725033Y-154397D01*
G01X711917Y-200564D02*
X711043Y-199689D01*
X710388Y-198231D01*
X709951Y-196188D01*
X710388Y-194439D01*
X711261Y-193272D01*
X712790Y-192397D01*
X718685D01*
Y-209897D01*
X711480D01*
X709951Y-208731D01*
X709078Y-206980D01*
X708641Y-204939D01*
X709078Y-202897D01*
X710388Y-201147D01*
X711917Y-200564D01*
X718685D01*
G01X700748Y-207564D02*
X699001Y-209022D01*
X697036Y-209897D01*
X695290D01*
X693543Y-209022D01*
X692233Y-207564D01*
X691578Y-205522D01*
X692015Y-203481D01*
X693106Y-201730D01*
X695071Y-200564D01*
X697691Y-199980D01*
X699220Y-198814D01*
X699875Y-196772D01*
X699438Y-194730D01*
X698346Y-193272D01*
X696818Y-192397D01*
X695290D01*
X693761Y-192980D01*
X692451Y-194439D01*
G01X681283Y-192397D02*
X676043D01*
G01X678663D02*
Y-209897D01*
G01X681283D02*
X676043D01*
G01X665530Y-192397D02*
Y-209897D01*
X656796D01*
G01X648466D02*
Y-192397D01*
G01X640170D02*
X648466Y-203189D01*
G01X638860Y-209897D02*
X644755Y-198231D01*
G01X781410Y-164897D02*
Y-147397D01*
X785776D01*
X787523Y-148272D01*
X788833Y-149439D01*
X789925Y-151188D01*
X790798Y-153231D01*
X791016Y-156147D01*
X790798Y-159064D01*
X789925Y-161106D01*
X788833Y-162856D01*
X787523Y-164022D01*
X785776Y-164897D01*
X781410D01*
G01X800438Y-157022D02*
X807425D01*
X806770Y-154980D01*
X805678Y-153814D01*
X804150Y-153231D01*
X802621Y-153522D01*
X801311Y-154397D01*
X800438Y-156439D01*
X800001Y-158189D01*
Y-159939D01*
X800438Y-161689D01*
X801530Y-163439D01*
X802840Y-164605D01*
X804368Y-164897D01*
X805896Y-164314D01*
X807425Y-162564D01*
G01X817938Y-162856D02*
X819030Y-164022D01*
X820558Y-164897D01*
X821868D01*
X823178Y-164314D01*
X824051Y-163439D01*
X824488Y-162273D01*
X824270Y-160522D01*
X823396Y-159647D01*
X819466Y-157897D01*
X818593Y-155855D01*
X819030Y-154397D01*
X819903Y-153522D01*
X821213Y-153231D01*
X822523Y-153522D01*
X823833Y-154397D01*
G01X838713Y-153231D02*
Y-164897D01*
G01Y-148564D02*
X838276Y-148272D01*
Y-147689D01*
X838713Y-147397D01*
X839150Y-147689D01*
Y-148272D01*
X838713Y-148564D01*
G01X853156Y-169272D02*
X854685Y-170439D01*
X856431Y-170730D01*
X857959Y-170439D01*
X859270Y-168981D01*
X860143Y-166939D01*
Y-153231D01*
G01Y-155564D02*
X859270Y-154397D01*
X857959Y-153522D01*
X856431Y-153231D01*
X854685Y-153814D01*
X853593Y-154980D01*
X852719Y-157022D01*
X852283Y-159064D01*
X852501Y-160814D01*
X853375Y-162856D01*
X854685Y-164314D01*
X856431Y-164897D01*
X857741Y-164605D01*
X859270Y-163439D01*
X860143Y-162273D01*
G01X870001Y-164897D02*
Y-153231D01*
G01Y-156147D02*
X870875Y-154689D01*
X872185Y-153522D01*
X873931Y-153231D01*
X875459Y-153522D01*
X876770Y-154689D01*
X877425Y-156730D01*
Y-164897D01*
G01X887938Y-157022D02*
X894925D01*
X894270Y-154980D01*
X893178Y-153814D01*
X891650Y-153231D01*
X890121Y-153522D01*
X888811Y-154397D01*
X887938Y-156439D01*
X887501Y-158189D01*
Y-159939D01*
X887938Y-161689D01*
X889030Y-163439D01*
X890340Y-164605D01*
X891868Y-164897D01*
X893396Y-164314D01*
X894925Y-162564D01*
G01X905656Y-164897D02*
Y-153231D01*
G01Y-155564D02*
X906748Y-154397D01*
X907840Y-153522D01*
X909368Y-153231D01*
X910459Y-153522D01*
X911770Y-154397D01*
G01X825596Y-209897D02*
Y-192397D01*
X831055D01*
X832801Y-193272D01*
X833893Y-194439D01*
X834330Y-196772D01*
X833893Y-199106D01*
X832583Y-200564D01*
X831055Y-201439D01*
X825596D01*
G01X831055D02*
X834330Y-209897D01*
G01X847463D02*
X846153Y-209605D01*
X844843Y-208439D01*
X843969Y-206397D01*
X843533Y-204064D01*
X843969Y-201730D01*
X844843Y-199689D01*
X846153Y-198522D01*
X847463Y-198231D01*
X848773Y-198522D01*
X850083Y-199689D01*
X850956Y-201730D01*
X851175Y-204064D01*
X850956Y-206397D01*
X850083Y-208439D01*
X848773Y-209605D01*
X847463Y-209897D01*
G01X861033D02*
Y-192397D01*
G01Y-201147D02*
X862125Y-199397D01*
X863435Y-198522D01*
X864745Y-198231D01*
X866709Y-198814D01*
X868020Y-199980D01*
X868893Y-202022D01*
Y-204355D01*
X868456Y-206689D01*
X867583Y-208439D01*
X866055Y-209605D01*
X864745Y-209897D01*
X863435Y-209605D01*
X862125Y-208731D01*
X861033Y-207273D01*
G01X952413Y-209897D02*
Y-192397D01*
X949793Y-195897D01*
G01Y-209897D02*
X955033D01*
G01X969913Y-192397D02*
X968166Y-192980D01*
X966856Y-194439D01*
X965983Y-196188D01*
X965328Y-198522D01*
X965110Y-201147D01*
X965328Y-203772D01*
X965983Y-206106D01*
X966856Y-207856D01*
X968166Y-209314D01*
X969913Y-209897D01*
X971659Y-209314D01*
X972970Y-207856D01*
X973843Y-206106D01*
X974498Y-203772D01*
X974716Y-201147D01*
X974498Y-198522D01*
X973843Y-196188D01*
X972970Y-194439D01*
X971659Y-192980D01*
X969913Y-192397D01*
G01X983483Y-210480D02*
X991343Y-192397D01*
G01X1004913Y-209897D02*
Y-192397D01*
X1002293Y-195897D01*
G01Y-209897D02*
X1007533D01*
G01X1018265Y-202606D02*
X1019793Y-200564D01*
X1021103Y-199397D01*
X1022850Y-198814D01*
X1024378Y-199397D01*
X1025470Y-200564D01*
X1026343Y-202314D01*
X1026561Y-204355D01*
X1026343Y-206106D01*
X1025470Y-207856D01*
X1024159Y-209314D01*
X1022631Y-209897D01*
X1020885Y-209314D01*
X1019356Y-207564D01*
X1018483Y-204939D01*
X1018265Y-202022D01*
X1018701Y-198231D01*
X1019356Y-196188D01*
X1020448Y-194147D01*
X1021976Y-192689D01*
X1023505Y-192397D01*
X1025033Y-192980D01*
X1026125Y-194439D01*
G01X1035983Y-210480D02*
X1043843Y-192397D01*
G01X1053265Y-195314D02*
X1054575Y-193564D01*
X1056103Y-192689D01*
X1057850Y-192397D01*
X1060033Y-192980D01*
X1061561Y-194439D01*
X1061998Y-196188D01*
X1061780Y-197939D01*
X1060906Y-199397D01*
X1056540Y-202314D01*
X1054575Y-204355D01*
X1053265Y-207273D01*
X1052828Y-209897D01*
X1061998D01*
G01X1074913Y-192397D02*
X1073166Y-192980D01*
X1071856Y-194439D01*
X1070983Y-196188D01*
X1070328Y-198522D01*
X1070110Y-201147D01*
X1070328Y-203772D01*
X1070983Y-206106D01*
X1071856Y-207856D01*
X1073166Y-209314D01*
X1074913Y-209897D01*
X1076659Y-209314D01*
X1077970Y-207856D01*
X1078843Y-206106D01*
X1079498Y-203772D01*
X1079716Y-201147D01*
X1079498Y-198522D01*
X1078843Y-196188D01*
X1077970Y-194439D01*
X1076659Y-192980D01*
X1074913Y-192397D01*
G01X1092413Y-209897D02*
Y-192397D01*
X1089793Y-195897D01*
G01Y-209897D02*
X1095033D01*
G01X1105765Y-195314D02*
X1107075Y-193564D01*
X1108603Y-192689D01*
X1110350Y-192397D01*
X1112533Y-192980D01*
X1114061Y-194439D01*
X1114498Y-196188D01*
X1114280Y-197939D01*
X1113406Y-199397D01*
X1109040Y-202314D01*
X1107075Y-204355D01*
X1105765Y-207273D01*
X1105328Y-209897D01*
X1114498D01*
G01X1000110Y-164897D02*
Y-147397D01*
X1004476D01*
X1006223Y-148272D01*
X1007533Y-149439D01*
X1008625Y-151188D01*
X1009498Y-153231D01*
X1009716Y-156147D01*
X1009498Y-159064D01*
X1008625Y-161106D01*
X1007533Y-162856D01*
X1006223Y-164022D01*
X1004476Y-164897D01*
X1000110D01*
G01X1026343D02*
Y-153231D01*
G01Y-155272D02*
X1025470Y-154106D01*
X1024159Y-153522D01*
X1022631Y-153231D01*
X1021103Y-153814D01*
X1019793Y-154980D01*
X1018919Y-156730D01*
X1018483Y-159064D01*
X1018919Y-161397D01*
X1019793Y-163147D01*
X1021103Y-164314D01*
X1022631Y-164897D01*
X1024159Y-164605D01*
X1025470Y-163731D01*
X1026343Y-162564D01*
G01X1039913Y-147397D02*
Y-164897D01*
G01X1036856Y-153231D02*
X1042970D01*
G01X1054138Y-157022D02*
X1061125D01*
X1060470Y-154980D01*
X1059378Y-153814D01*
X1057850Y-153231D01*
X1056321Y-153522D01*
X1055011Y-154397D01*
X1054138Y-156439D01*
X1053701Y-158189D01*
Y-159939D01*
X1054138Y-161689D01*
X1055230Y-163439D01*
X1056540Y-164605D01*
X1058068Y-164897D01*
X1059596Y-164314D01*
X1061125Y-162564D01*
M02*
